# T6G (Grand Teton) — schematic netlist excerpt (pin names and nets, part order shuffled) for the footprints in the layout excerpt that follows; sources: Cadence DE-HDL packaged netlist, KiCad conversion of 04192023_DAF0TMB3IC0_F0TG_MB_C_brd_V02_OCP.brd

C2616  Q_CAP  22UF 4V 20% X6S  pkg C0402  page 70 : A = PVDD11_S3_P0 ; B = GND
R406  Q_RES  4.7K 5% EMPTY  pkg 0402LF  page 160 : A = PVDD18_S5_P0 ; B = SMB_CPU0_CPU1_SEC_SDA_R2
C654  Q_CAP  1UF 4V 20% X6S  pkg 0201  page 290 : A = P0V9_CPU0_RT1_2A ; B = GND

(kicad_pcb
	(version 20260206)
	(generator "pcbnew")
	(generator_version "10.0")
	(general
		(thickness 1.6)
		(legacy_teardrops no)
	)
	(paper "A4")
	(title_block
		(title "04192023_DAF0TMB3IC0_F0TG_MB_C_brd_V02_OCP.brd")
		(comment 1 "Grand Teton / footprints 7943-7945 of 8354")
	)
	(layers
		(0 "F.Cu" signal "TOP")
		(4 "In1.Cu" signal "GND")
		(6 "In2.Cu" signal "IN1")
		(8 "In3.Cu" signal "GND1")
		(10 "In4.Cu" signal "IN2")
		(12 "In5.Cu" signal "GND2")
		(14 "In6.Cu" signal "IN3")
		(16 "In7.Cu" signal "GND3")
		(18 "In8.Cu" signal "VCC")
		(20 "In9.Cu" signal "VCC1")
		(22 "In10.Cu" signal "GND4")
		(24 "In11.Cu" signal "IN4")
		(26 "In12.Cu" signal "GND5")
		(28 "In13.Cu" signal "IN5")
		(30 "In14.Cu" signal "GND6")
		(32 "In15.Cu" signal "IN6")
		(34 "In16.Cu" signal "GND7")
		(2 "B.Cu" signal "BOTTOM")
		(9 "F.Adhes" user "F.Adhesive")
		(11 "B.Adhes" user "B.Adhesive")
		(13 "F.Paste" user "Package Geometry/Pastemask Top")
		(15 "B.Paste" user "Package Geometry/Pastemask Bottom")
		(5 "F.SilkS" user "Ref Des/Silkscreen Top")
		(7 "B.SilkS" user "Ref Des/Silkscreen Bottom")
		(1 "F.Mask" user "Board Geometry/Soldermask Top")
		(3 "B.Mask" user "Board Geometry/Soldermask Bottom")
		(17 "Dwgs.User" user "User.Drawings")
		(19 "Cmts.User" user "User.Comments")
		(21 "Eco1.User" user "User.Eco1")
		(23 "Eco2.User" user "User.Eco2")
		(25 "Edge.Cuts" user "Board Geometry/Outline")
		(27 "Margin" user)
		(31 "F.CrtYd" user "Package Geometry/Place Bound Top")
		(29 "B.CrtYd" user "Package Geometry/Place Bound Bottom")
		(35 "F.Fab" user "Ref Des/Assembly Top")
		(33 "B.Fab" user "Ref Des/Assembly Bottom")
	)
	(footprint ""
		(layer "B.Cu")
		(at 358.796082 -258.795012 180)
		(property "Reference" "C2616"
			(at 0 0 0)
			(layer "B.SilkS")
			(hide yes)
			(effects
				(font
					(size 1.27 1.27)
				)
				(justify mirror)
			)
		)
		(property "Value" ""
			(at 0 0 0)
			(layer "B.Fab")
			(effects
				(font
					(size 1.27 1.27)
				)
				(justify mirror)
			)
		)
		(duplicate_pad_numbers_are_jumpers no)
		(fp_line
			(start 0.7874 0.4064)
			(end 0.7874 -0.4064)
			(stroke
				(width 0.1524)
				(type default)
			)
			(layer "B.SilkS")
		)
		(fp_line
			(start 0.7874 -0.4064)
			(end -0.7874 -0.4064)
			(stroke
				(width 0.1524)
				(type default)
			)
			(layer "B.SilkS")
		)
		(fp_line
			(start -0.7874 0.4064)
			(end 0.7874 0.4064)
			(stroke
				(width 0.1524)
				(type default)
			)
			(layer "B.SilkS")
		)
		(fp_line
			(start -0.7874 -0.4064)
			(end -0.7874 0.4064)
			(stroke
				(width 0.1524)
				(type default)
			)
			(layer "B.SilkS")
		)
		(fp_line
			(start 0.67945 0.3048)
			(end 0.67945 -0.305054)
			(stroke
				(width 0.1)
				(type default)
			)
			(layer "B.Fab")
		)
		(fp_line
			(start 0.67945 -0.305054)
			(end 0.12065 -0.305054)
			(stroke
				(width 0.1)
				(type default)
			)
			(layer "B.Fab")
		)
		(fp_line
			(start 0.12065 0.3048)
			(end 0.67945 0.3048)
			(stroke
				(width 0.1)
				(type default)
			)
			(layer "B.Fab")
		)
		(fp_line
			(start 0.12065 0.2794)
			(end 0.12065 0.3048)
			(stroke
				(width 0.1)
				(type default)
			)
			(layer "B.Fab")
		)
		(fp_line
			(start 0.12065 -0.2794)
			(end -0.12065 -0.2794)
			(stroke
				(width 0.1)
				(type default)
			)
			(layer "B.Fab")
		)
		(fp_line
			(start 0.12065 -0.305054)
			(end 0.12065 -0.2794)
			(stroke
				(width 0.1)
				(type default)
			)
			(layer "B.Fab")
		)
		(fp_line
			(start -0.120396 0.3048)
			(end -0.120396 0.2794)
			(stroke
				(width 0.1)
				(type default)
			)
			(layer "B.Fab")
		)
		(fp_line
			(start -0.120396 0.2794)
			(end 0.12065 0.2794)
			(stroke
				(width 0.1)
				(type default)
			)
			(layer "B.Fab")
		)
		(fp_line
			(start -0.12065 -0.2794)
			(end -0.12065 -0.3048)
			(stroke
				(width 0.1)
				(type default)
			)
			(layer "B.Fab")
		)
		(fp_line
			(start -0.12065 -0.3048)
			(end -0.67945 -0.3048)
			(stroke
				(width 0.1)
				(type default)
			)
			(layer "B.Fab")
		)
		(fp_line
			(start -0.67945 0.3048)
			(end -0.120396 0.3048)
			(stroke
				(width 0.1)
				(type default)
			)
			(layer "B.Fab")
		)
		(fp_line
			(start -0.67945 -0.3048)
			(end -0.67945 0.3048)
			(stroke
				(width 0.1)
				(type default)
			)
			(layer "B.Fab")
		)
		(pad "1" smd circle
			(at 0.40005 0)
			(size 0 0)
			(layers "B.Cu" "B.Mask" "B.Paste")
			(net "PVDD11_S3_P0")
		)
		(pad "2" smd circle
			(at -0.40005 0)
			(size 0 0)
			(layers "B.Cu" "B.Mask" "B.Paste")
			(net "GND")
		)
	)
	(footprint ""
		(layer "B.Cu")
		(at 244.475 -229.489)
		(property "Reference" "R406"
			(at 0 0 0)
			(layer "B.SilkS")
			(hide yes)
			(effects
				(font
					(size 1.27 1.27)
				)
				(justify mirror)
			)
		)
		(property "Value" ""
			(at 0 0 0)
			(layer "B.Fab")
			(effects
				(font
					(size 1.27 1.27)
				)
				(justify mirror)
			)
		)
		(duplicate_pad_numbers_are_jumpers no)
		(fp_line
			(start -0.7874 -0.4064)
			(end -0.7874 0.4064)
			(stroke
				(width 0.1524)
				(type default)
			)
			(layer "B.SilkS")
		)
		(fp_line
			(start -0.7874 0.4064)
			(end 0.7874 0.4064)
			(stroke
				(width 0.1524)
				(type default)
			)
			(layer "B.SilkS")
		)
		(fp_line
			(start 0.7874 -0.4064)
			(end -0.7874 -0.4064)
			(stroke
				(width 0.1524)
				(type default)
			)
			(layer "B.SilkS")
		)
		(fp_line
			(start 0.7874 0.4064)
			(end 0.7874 -0.4064)
			(stroke
				(width 0.1524)
				(type default)
			)
			(layer "B.SilkS")
		)
		(fp_line
			(start -0.67945 -0.3048)
			(end -0.67945 0.3048)
			(stroke
				(width 0.1)
				(type default)
			)
			(layer "B.Fab")
		)
		(fp_line
			(start -0.67945 0.3048)
			(end -0.120396 0.3048)
			(stroke
				(width 0.1)
				(type default)
			)
			(layer "B.Fab")
		)
		(fp_line
			(start -0.12065 -0.3048)
			(end -0.67945 -0.3048)
			(stroke
				(width 0.1)
				(type default)
			)
			(layer "B.Fab")
		)
		(fp_line
			(start -0.12065 -0.2794)
			(end -0.12065 -0.3048)
			(stroke
				(width 0.1)
				(type default)
			)
			(layer "B.Fab")
		)
		(fp_line
			(start -0.120396 0.2794)
			(end 0.12065 0.2794)
			(stroke
				(width 0.1)
				(type default)
			)
			(layer "B.Fab")
		)
		(fp_line
			(start -0.120396 0.3048)
			(end -0.120396 0.2794)
			(stroke
				(width 0.1)
				(type default)
			)
			(layer "B.Fab")
		)
		(fp_line
			(start 0.12065 -0.305054)
			(end 0.12065 -0.2794)
			(stroke
				(width 0.1)
				(type default)
			)
			(layer "B.Fab")
		)
		(fp_line
			(start 0.12065 -0.2794)
			(end -0.12065 -0.2794)
			(stroke
				(width 0.1)
				(type default)
			)
			(layer "B.Fab")
		)
		(fp_line
			(start 0.12065 0.2794)
			(end 0.12065 0.3048)
			(stroke
				(width 0.1)
				(type default)
			)
			(layer "B.Fab")
		)
		(fp_line
			(start 0.12065 0.3048)
			(end 0.67945 0.3048)
			(stroke
				(width 0.1)
				(type default)
			)
			(layer "B.Fab")
		)
		(fp_line
			(start 0.67945 -0.305054)
			(end 0.12065 -0.305054)
			(stroke
				(width 0.1)
				(type default)
			)
			(layer "B.Fab")
		)
		(fp_line
			(start 0.67945 0.3048)
			(end 0.67945 -0.305054)
			(stroke
				(width 0.1)
				(type default)
			)
			(layer "B.Fab")
		)
		(pad "1" smd circle
			(at 0.40005 0 180)
			(size 0 0)
			(layers "B.Cu" "B.Mask" "B.Paste")
			(net "PVDD18_S5_P0")
		)
		(pad "2" smd circle
			(at -0.40005 0 180)
			(size 0 0)
			(layers "B.Cu" "B.Mask" "B.Paste")
			(net "SMB_CPU0_CPU1_SEC_SDA_R2")
		)
	)
	(footprint ""
		(layer "B.Cu")
		(at 338.306156 -395.148562 90)
		(property "Reference" "C654"
			(at 0 0 90)
			(layer "B.SilkS")
			(hide yes)
			(effects
				(font
					(size 1.27 1.27)
				)
				(justify mirror)
			)
		)
		(property "Value" ""
			(at 0 0 90)
			(layer "B.Fab")
			(effects
				(font
					(size 1.27 1.27)
				)
				(justify mirror)
			)
		)
		(duplicate_pad_numbers_are_jumpers no)
		(fp_line
			(start 0.299974 -0.150114)
			(end -0.299974 -0.150114)
			(stroke
				(width 0.1)
				(type default)
			)
			(layer "B.Fab")
		)
		(fp_line
			(start -0.299974 -0.150114)
			(end -0.299974 0.150114)
			(stroke
				(width 0.1)
				(type default)
			)
			(layer "B.Fab")
		)
		(fp_line
			(start 0.299974 0.150114)
			(end 0.299974 -0.150114)
			(stroke
				(width 0.1)
				(type default)
			)
			(layer "B.Fab")
		)
		(fp_line
			(start -0.299974 0.150114)
			(end 0.299974 0.150114)
			(stroke
				(width 0.1)
				(type default)
			)
			(layer "B.Fab")
		)
		(pad "1" smd rect
			(at 0.2667 0 270)
			(size 0.3048 0.381)
			(layers "B.Cu" "B.Mask" "B.Paste")
			(net "P0V9_CPU0_RT1_2A")
		)
		(pad "2" smd rect
			(at -0.2667 0 270)
			(size 0.3048 0.381)
			(layers "B.Cu" "B.Mask" "B.Paste")
			(net "GND")
		)
	)
)
